# T6G (Grand Teton) — schematic netlist excerpt (pin names and nets, part order shuffled) for the footprints in the layout excerpt that follows; sources: Cadence DE-HDL packaged netlist, KiCad conversion of 04192023_DAF0TMB3IC0_F0TG_MB_C_brd_V02_OCP.brd

C7500  Q_CAP  0.1UF 10V 10% X7S  pkg C0201  page 184 : A = P1V8_AUX ; B = GND
PR80  Q_RES  2.2 1% CHIP  pkg 0402LF  page 201 : A = PVDDCR_CPU1_P0_PVCC ; B = PVDDCR_CPU1_P0_VCC2
PC456_1  Q_CAP  22UF 4V 20% X6S  pkg C0805  page 222 : A = PVDDIO_P1 ; B = GND

(kicad_pcb
	(version 20260206)
	(generator "pcbnew")
	(generator_version "10.0")
	(general
		(thickness 1.6)
		(legacy_teardrops no)
	)
	(paper "A4")
	(title_block
		(title "04192023_DAF0TMB3IC0_F0TG_MB_C_brd_V02_OCP.brd")
		(comment 1 "Grand Teton / footprints 5638-5641 of 8354")
	)
	(layers
		(0 "F.Cu" signal "TOP")
		(4 "In1.Cu" signal "GND")
		(6 "In2.Cu" signal "IN1")
		(8 "In3.Cu" signal "GND1")
		(10 "In4.Cu" signal "IN2")
		(12 "In5.Cu" signal "GND2")
		(14 "In6.Cu" signal "IN3")
		(16 "In7.Cu" signal "GND3")
		(18 "In8.Cu" signal "VCC")
		(20 "In9.Cu" signal "VCC1")
		(22 "In10.Cu" signal "GND4")
		(24 "In11.Cu" signal "IN4")
		(26 "In12.Cu" signal "GND5")
		(28 "In13.Cu" signal "IN5")
		(30 "In14.Cu" signal "GND6")
		(32 "In15.Cu" signal "IN6")
		(34 "In16.Cu" signal "GND7")
		(2 "B.Cu" signal "BOTTOM")
		(9 "F.Adhes" user "F.Adhesive")
		(11 "B.Adhes" user "B.Adhesive")
		(13 "F.Paste" user "Package Geometry/Pastemask Top")
		(15 "B.Paste" user "Package Geometry/Pastemask Bottom")
		(5 "F.SilkS" user "Ref Des/Silkscreen Top")
		(7 "B.SilkS" user "Ref Des/Silkscreen Bottom")
		(1 "F.Mask" user "Board Geometry/Soldermask Top")
		(3 "B.Mask" user "Board Geometry/Soldermask Bottom")
		(17 "Dwgs.User" user "User.Drawings")
		(19 "Cmts.User" user "User.Comments")
		(21 "Eco1.User" user "User.Eco1")
		(23 "Eco2.User" user "User.Eco2")
		(25 "Edge.Cuts" user "Board Geometry/Outline")
		(27 "Margin" user)
		(31 "F.CrtYd" user "Package Geometry/Place Bound Top")
		(29 "B.CrtYd" user "Package Geometry/Place Bound Bottom")
		(35 "F.Fab" user "Ref Des/Assembly Top")
		(33 "B.Fab" user "Ref Des/Assembly Bottom")
	)
	(footprint ""
		(layer "B.Cu")
		(at 324.390512 -336.047334 -90)
		(property "Reference" "PR80"
			(at 0 0 90)
			(layer "B.SilkS")
			(hide yes)
			(effects
				(font
					(size 1.27 1.27)
				)
				(justify mirror)
			)
		)
		(property "Value" ""
			(at 0 0 90)
			(layer "B.Fab")
			(effects
				(font
					(size 1.27 1.27)
				)
				(justify mirror)
			)
		)
		(duplicate_pad_numbers_are_jumpers no)
		(fp_line
			(start -0.7874 0.4064)
			(end 0.7874 0.4064)
			(stroke
				(width 0.1524)
				(type default)
			)
			(layer "B.SilkS")
		)
		(fp_line
			(start 0.7874 0.4064)
			(end 0.7874 -0.4064)
			(stroke
				(width 0.1524)
				(type default)
			)
			(layer "B.SilkS")
		)
		(fp_line
			(start -0.7874 -0.4064)
			(end -0.7874 0.4064)
			(stroke
				(width 0.1524)
				(type default)
			)
			(layer "B.SilkS")
		)
		(fp_line
			(start 0.7874 -0.4064)
			(end -0.7874 -0.4064)
			(stroke
				(width 0.1524)
				(type default)
			)
			(layer "B.SilkS")
		)
		(fp_line
			(start -0.67945 0.3048)
			(end -0.120396 0.3048)
			(stroke
				(width 0.1)
				(type default)
			)
			(layer "B.Fab")
		)
		(fp_line
			(start -0.120396 0.3048)
			(end -0.120396 0.2794)
			(stroke
				(width 0.1)
				(type default)
			)
			(layer "B.Fab")
		)
		(fp_line
			(start 0.12065 0.3048)
			(end 0.67945 0.3048)
			(stroke
				(width 0.1)
				(type default)
			)
			(layer "B.Fab")
		)
		(fp_line
			(start 0.67945 0.3048)
			(end 0.67945 -0.305054)
			(stroke
				(width 0.1)
				(type default)
			)
			(layer "B.Fab")
		)
		(fp_line
			(start -0.120396 0.2794)
			(end 0.12065 0.2794)
			(stroke
				(width 0.1)
				(type default)
			)
			(layer "B.Fab")
		)
		(fp_line
			(start 0.12065 0.2794)
			(end 0.12065 0.3048)
			(stroke
				(width 0.1)
				(type default)
			)
			(layer "B.Fab")
		)
		(fp_line
			(start -0.12065 -0.2794)
			(end -0.12065 -0.3048)
			(stroke
				(width 0.1)
				(type default)
			)
			(layer "B.Fab")
		)
		(fp_line
			(start 0.12065 -0.2794)
			(end -0.12065 -0.2794)
			(stroke
				(width 0.1)
				(type default)
			)
			(layer "B.Fab")
		)
		(fp_line
			(start -0.67945 -0.3048)
			(end -0.67945 0.3048)
			(stroke
				(width 0.1)
				(type default)
			)
			(layer "B.Fab")
		)
		(fp_line
			(start -0.12065 -0.3048)
			(end -0.67945 -0.3048)
			(stroke
				(width 0.1)
				(type default)
			)
			(layer "B.Fab")
		)
		(fp_line
			(start 0.12065 -0.305054)
			(end 0.12065 -0.2794)
			(stroke
				(width 0.1)
				(type default)
			)
			(layer "B.Fab")
		)
		(fp_line
			(start 0.67945 -0.305054)
			(end 0.12065 -0.305054)
			(stroke
				(width 0.1)
				(type default)
			)
			(layer "B.Fab")
		)
		(pad "1" smd circle
			(at 0.40005 0 90)
			(size 0 0)
			(layers "B.Cu" "B.Mask" "B.Paste")
			(net "PVDDCR_CPU1_P0_PVCC")
		)
		(pad "2" smd circle
			(at -0.40005 0 90)
			(size 0 0)
			(layers "B.Cu" "B.Mask" "B.Paste")
			(net "PVDDCR_CPU1_P0_VCC2")
		)
	)
	(footprint ""
		(layer "B.Cu")
		(at 49.401476 -337.985354 -90)
		(property "Reference" "PC456_1"
			(at 0 0 90)
			(layer "B.SilkS")
			(hide yes)
			(effects
				(font
					(size 1.27 1.27)
				)
				(justify mirror)
			)
		)
		(property "Value" ""
			(at 0 0 90)
			(layer "B.Fab")
			(effects
				(font
					(size 1.27 1.27)
				)
				(justify mirror)
			)
		)
		(duplicate_pad_numbers_are_jumpers no)
		(fp_line
			(start -1.524 0.762)
			(end 1.524 0.762)
			(stroke
				(width 0.1524)
				(type default)
			)
			(layer "B.SilkS")
		)
		(fp_line
			(start 1.524 0.762)
			(end 1.524 -0.762)
			(stroke
				(width 0.1524)
				(type default)
			)
			(layer "B.SilkS")
		)
		(fp_line
			(start -1.524 -0.762)
			(end -1.524 0.762)
			(stroke
				(width 0.1524)
				(type default)
			)
			(layer "B.SilkS")
		)
		(fp_line
			(start 1.524 -0.762)
			(end -1.524 -0.762)
			(stroke
				(width 0.1524)
				(type default)
			)
			(layer "B.SilkS")
		)
		(fp_line
			(start -1.1049 0.724916)
			(end -1.1049 -0.724916)
			(stroke
				(width 0.1)
				(type default)
			)
			(layer "B.Fab")
		)
		(fp_line
			(start 1.1049 0.724916)
			(end -1.1049 0.724916)
			(stroke
				(width 0.1)
				(type default)
			)
			(layer "B.Fab")
		)
		(fp_line
			(start -1.1049 -0.724916)
			(end 1.1049 -0.724916)
			(stroke
				(width 0.1)
				(type default)
			)
			(layer "B.Fab")
		)
		(fp_line
			(start 1.1049 -0.724916)
			(end 1.1049 0.724916)
			(stroke
				(width 0.1)
				(type default)
			)
			(layer "B.Fab")
		)
		(pad "1" smd rect
			(at 0.889 0 270)
			(size 1.016 1.27)
			(layers "B.Cu" "B.Mask" "B.Paste")
			(net "PVDDIO_P1")
		)
		(pad "2" smd rect
			(at -0.889 0 270)
			(size 1.016 1.27)
			(layers "B.Cu" "B.Mask" "B.Paste")
			(net "GND")
		)
	)
	(footprint ""
		(layer "B.Cu")
		(at 423.139616 -495.255042)
		(property "Reference" "LBL_2"
			(at 0 0 0)
			(layer "B.SilkS")
			(hide yes)
			(effects
				(font
					(size 1.27 1.27)
				)
				(justify mirror)
			)
		)
		(property "Value" ""
			(at 0 0 0)
			(layer "B.Fab")
			(effects
				(font
					(size 1.27 1.27)
				)
				(justify mirror)
			)
		)
		(duplicate_pad_numbers_are_jumpers no)
		(pad "1" smd circle
			(at 0 0 180)
			(size 0.762 0.762)
			(layers "B.Cu" "B.Mask" "B.Paste")
			(net "Net_10851")
		)
	)
	(footprint ""
		(layer "B.Cu")
		(at 225.679 -332.105)
		(property "Reference" "C7500"
			(at 0 0 0)
			(layer "B.SilkS")
			(hide yes)
			(effects
				(font
					(size 1.27 1.27)
				)
				(justify mirror)
			)
		)
		(property "Value" ""
			(at 0 0 0)
			(layer "B.Fab")
			(effects
				(font
					(size 1.27 1.27)
				)
				(justify mirror)
			)
		)
		(duplicate_pad_numbers_are_jumpers no)
		(fp_line
			(start -0.299974 -0.150114)
			(end -0.299974 0.150114)
			(stroke
				(width 0.1)
				(type default)
			)
			(layer "B.Fab")
		)
		(fp_line
			(start -0.299974 0.150114)
			(end 0.299974 0.150114)
			(stroke
				(width 0.1)
				(type default)
			)
			(layer "B.Fab")
		)
		(fp_line
			(start 0.299974 -0.150114)
			(end -0.299974 -0.150114)
			(stroke
				(width 0.1)
				(type default)
			)
			(layer "B.Fab")
		)
		(fp_line
			(start 0.299974 0.150114)
			(end 0.299974 -0.150114)
			(stroke
				(width 0.1)
				(type default)
			)
			(layer "B.Fab")
		)
		(pad "1" smd rect
			(at 0.2667 0 180)
			(size 0.3048 0.381)
			(layers "B.Cu" "B.Mask" "B.Paste")
			(net "P1V8_AUX")
		)
		(pad "2" smd rect
			(at -0.2667 0 180)
			(size 0.3048 0.381)
			(layers "B.Cu" "B.Mask" "B.Paste")
			(net "GND")
		)
	)
)
